(kicad_pcb
	(version 20260206)
	(generator "pcbnew")
	(generator_version "10.0")
	(general
		(thickness 1.6)
		(legacy_teardrops no)
	)
	(paper "A4")
	(title_block
		(title "01162023_DA0F0TEBIF0_F0T_Expander_BD_F_brd_V02_OCP.brd")
		(comment 1 "Grand Teton / footprints 4137-4141 of 9728")
	)
	(layers
		(0 "F.Cu" signal "TOP")
		(4 "In1.Cu" signal "GND")
		(6 "In2.Cu" signal "VCC")
		(8 "In3.Cu" signal "VCC1")
		(10 "In4.Cu" signal "GND1")
		(12 "In5.Cu" signal "IN1")
		(14 "In6.Cu" signal "GND2")
		(16 "In7.Cu" signal "IN2")
		(18 "In8.Cu" signal "GND3")
		(20 "In9.Cu" signal "IN3")
		(22 "In10.Cu" signal "GND4")
		(24 "In11.Cu" signal "IN4")
		(26 "In12.Cu" signal "GND5")
		(28 "In13.Cu" signal "IN5")
		(30 "In14.Cu" signal "GND6")
		(32 "In15.Cu" signal "IN6")
		(34 "In16.Cu" signal "GND7")
		(2 "B.Cu" signal "BOTTOM")
		(9 "F.Adhes" user "F.Adhesive")
		(11 "B.Adhes" user "B.Adhesive")
		(13 "F.Paste" user "Package Geometry/Pastemask Top")
		(15 "B.Paste" user "Package Geometry/Pastemask Bottom")
		(5 "F.SilkS" user "Ref Des/Silkscreen Top")
		(7 "B.SilkS" user "Ref Des/Silkscreen Bottom")
		(1 "F.Mask" user "Board Geometry/Soldermask Top")
		(3 "B.Mask" user "Board Geometry/Soldermask Bottom")
		(17 "Dwgs.User" user "User.Drawings")
		(19 "Cmts.User" user "User.Comments")
		(21 "Eco1.User" user "User.Eco1")
		(23 "Eco2.User" user "User.Eco2")
		(25 "Edge.Cuts" user "Board Geometry/Outline")
		(27 "Margin" user)
		(31 "F.CrtYd" user "Package Geometry/Place Bound Top")
		(29 "B.CrtYd" user "Package Geometry/Place Bound Bottom")
		(35 "F.Fab" user "Ref Des/Assembly Top")
		(33 "B.Fab" user "Ref Des/Assembly Bottom")
	)
	(footprint ""
		(layer "F.Cu")
		(at 89.649808 -270.89989)
		(property "Reference" "H96"
			(at -2.967482 -9.050528 0)
			(unlocked yes)
			(layer "F.SilkS")
			(effects
				(font
					(size 0.7874 0.5842)
					(thickness 0.1524)
				)
				(justify left)
			)
		)
		(property "Value" ""
			(at 0 0 0)
			(layer "F.Fab")
			(effects
				(font
					(size 1.27 1.27)
				)
			)
		)
		(duplicate_pad_numbers_are_jumpers no)
		(fp_arc
			(start -5.469382 -5.83819)
			(mid 3.181563 -7.340126)
			(end 7.999984 0)
			(stroke
				(width 0.1524)
				(type default)
			)
			(layer "F.SilkS")
		)
		(fp_arc
			(start 7.999984 0)
			(mid -0.337504 7.99289)
			(end -7.971536 -0.67437)
			(stroke
				(width 0.1524)
				(type default)
			)
			(layer "F.SilkS")
		)
		(fp_arc
			(start -5.443474 -5.862574)
			(mid 3.197823 -7.333049)
			(end 7.999984 0)
			(stroke
				(width 0.1524)
				(type default)
			)
			(layer "B.SilkS")
		)
		(fp_arc
			(start 7.999984 0)
			(mid -0.300418 7.994298)
			(end -7.977378 -0.600456)
			(stroke
				(width 0.1524)
				(type default)
			)
			(layer "B.SilkS")
		)
		(fp_circle
			(center 0 0)
			(end 7.999984 0)
			(stroke
				(width 0.1)
				(type default)
			)
			(fill no)
			(layer "B.Fab")
		)
		(fp_circle
			(center 0 0)
			(end 7.999984 0)
			(stroke
				(width 0.1)
				(type default)
			)
			(fill no)
			(layer "F.Fab")
		)
		(pad "" np_thru_hole circle
			(at 0 0)
			(size 4.5212 4.5212)
			(drill 4.5212)
			(layers "*.Cu" "*.Mask")
			(clearance 0.381)
			(thermal_gap 0.381)
		)
		(pad "2" thru_hole circle
			(at 3.6322 0)
			(size 0.762 0.762)
			(drill 0.5588)
			(layers "*.Cu" "*.Mask")
			(remove_unused_layers no)
			(net "GND")
			(clearance 0.1524)
			(thermal_gap 0.1524)
		)
		(pad "3" thru_hole circle
			(at 2.568448 -2.568448)
			(size 0.762 0.762)
			(drill 0.5588)
			(layers "*.Cu" "*.Mask")
			(remove_unused_layers no)
			(net "GND")
			(clearance 0.1524)
			(thermal_gap 0.1524)
		)
		(pad "4" thru_hole circle
			(at 0 -3.6322)
			(size 0.762 0.762)
			(drill 0.5588)
			(layers "*.Cu" "*.Mask")
			(remove_unused_layers no)
			(net "GND")
			(clearance 0.1524)
			(thermal_gap 0.1524)
		)
		(pad "5" thru_hole circle
			(at -2.568448 -2.568448)
			(size 0.762 0.762)
			(drill 0.5588)
			(layers "*.Cu" "*.Mask")
			(remove_unused_layers no)
			(net "GND")
			(clearance 0.1524)
			(thermal_gap 0.1524)
		)
		(pad "6" thru_hole circle
			(at -3.6322 0)
			(size 0.762 0.762)
			(drill 0.5588)
			(layers "*.Cu" "*.Mask")
			(remove_unused_layers no)
			(net "GND")
			(clearance 0.1524)
			(thermal_gap 0.1524)
		)
		(pad "7" thru_hole circle
			(at -2.568448 2.568448)
			(size 0.762 0.762)
			(drill 0.5588)
			(layers "*.Cu" "*.Mask")
			(remove_unused_layers no)
			(net "GND")
			(clearance 0.1524)
			(thermal_gap 0.1524)
		)
		(pad "8" thru_hole circle
			(at 0 3.6322)
			(size 0.762 0.762)
			(drill 0.5588)
			(layers "*.Cu" "*.Mask")
			(remove_unused_layers no)
			(net "GND")
			(clearance 0.1524)
			(thermal_gap 0.1524)
		)
		(pad "9" thru_hole circle
			(at 2.568448 2.568448)
			(size 0.762 0.762)
			(drill 0.5588)
			(layers "*.Cu" "*.Mask")
			(remove_unused_layers no)
			(net "GND")
			(clearance 0.1524)
			(thermal_gap 0.1524)
		)
		(zone
			(layer "F.Cu")
			(hatch none 0.5)
			(connect_pads
				(clearance 0)
			)
			(min_thickness 0.25)
			(keepout
				(tracks not_allowed)
				(vias allowed)
				(pads allowed)
				(copperpour not_allowed)
				(footprints allowed)
			)
			(placement
				(enabled no)
				(sheetname "")
			)
			(fill
				(thermal_gap 0.5)
				(thermal_bridge_width 0.5)
				(island_removal_mode 0)
			)
			(polygon
				(pts
					(arc
						(start 89.649808 -262.899906)
						(mid 81.649824 -270.89989)
						(end 89.649808 -278.899874)
					)
					(arc
						(start 89.649808 -275.64969)
						(mid 84.900008 -270.89989)
						(end 89.649808 -266.15009)
					)
				)
			)
		)
		(zone
			(layer "F.Cu")
			(hatch none 0.5)
			(connect_pads
				(clearance 0)
			)
			(min_thickness 0.25)
			(keepout
				(tracks not_allowed)
				(vias allowed)
				(pads allowed)
				(copperpour not_allowed)
				(footprints allowed)
			)
			(placement
				(enabled no)
				(sheetname "")
			)
			(fill
				(thermal_gap 0.5)
				(thermal_bridge_width 0.5)
				(island_removal_mode 0)
			)
			(polygon
				(pts
					(arc
						(start 89.649808 -262.899906)
						(mid 97.649792 -270.89989)
						(end 89.649808 -278.899874)
					)
					(arc
						(start 89.649808 -275.64969)
						(mid 94.399608 -270.89989)
						(end 89.649808 -266.15009)
					)
				)
			)
		)
		(zone
			(layers "F.Cu" "B.Cu" "In1.Cu" "In2.Cu" "In3.Cu" "In4.Cu" "In5.Cu" "In6.Cu"
				"In7.Cu" "In8.Cu" "In9.Cu" "In10.Cu" "In11.Cu" "In12.Cu" "In13.Cu" "In14.Cu"
				"In15.Cu" "In16.Cu"
			)
			(hatch none 0.5)
			(connect_pads
				(clearance 0)
			)
			(min_thickness 0.25)
			(keepout
				(tracks not_allowed)
				(vias allowed)
				(pads allowed)
				(copperpour not_allowed)
				(footprints allowed)
			)
			(placement
				(enabled no)
				(sheetname "")
			)
			(fill
				(thermal_gap 0.5)
				(thermal_bridge_width 0.5)
				(island_removal_mode 0)
			)
			(polygon
				(pts
					(arc
						(start 92.415868 -270.89989)
						(mid 86.883748 -270.89989)
						(end 92.415868 -270.89989)
					)
				)
			)
		)
		(zone
			(layer "B.Cu")
			(hatch none 0.5)
			(connect_pads
				(clearance 0)
			)
			(min_thickness 0.25)
			(keepout
				(tracks not_allowed)
				(vias allowed)
				(pads allowed)
				(copperpour not_allowed)
				(footprints allowed)
			)
			(placement
				(enabled no)
				(sheetname "")
			)
			(fill
				(thermal_gap 0.5)
				(thermal_bridge_width 0.5)
				(island_removal_mode 0)
			)
			(polygon
				(pts
					(arc
						(start 89.649808 -265.89609)
						(mid 84.646008 -270.89989)
						(end 89.649808 -275.90369)
					)
					(arc
						(start 89.649808 -275.42109)
						(mid 85.128608 -270.89989)
						(end 89.649808 -266.37869)
					)
				)
			)
		)
		(zone
			(layer "B.Cu")
			(hatch none 0.5)
			(connect_pads
				(clearance 0)
			)
			(min_thickness 0.25)
			(keepout
				(tracks not_allowed)
				(vias allowed)
				(pads allowed)
				(copperpour not_allowed)
				(footprints allowed)
			)
			(placement
				(enabled no)
				(sheetname "")
			)
			(fill
				(thermal_gap 0.5)
				(thermal_bridge_width 0.5)
				(island_removal_mode 0)
			)
			(polygon
				(pts
					(arc
						(start 89.649808 -265.89609)
						(mid 94.653608 -270.89989)
						(end 89.649808 -275.90369)
					)
					(arc
						(start 89.649808 -275.42109)
						(mid 94.171008 -270.89989)
						(end 89.649808 -266.37869)
					)
				)
			)
		)
	)
	(footprint ""
		(layer "F.Cu")
		(at 255.01346 -195.573396 90)
		(property "Reference" "R5066"
			(at 0 0 90)
			(layer "F.SilkS")
			(hide yes)
			(effects
				(font
					(size 1.27 1.27)
				)
			)
		)
		(property "Value" ""
			(at 0 0 90)
			(layer "F.Fab")
			(effects
				(font
					(size 1.27 1.27)
				)
			)
		)
		(duplicate_pad_numbers_are_jumpers no)
		(fp_line
			(start 0.7874 -0.4064)
			(end 0.7874 0.4064)
			(stroke
				(width 0.1524)
				(type default)
			)
			(layer "F.SilkS")
		)
		(fp_line
			(start -0.7874 -0.4064)
			(end 0.7874 -0.4064)
			(stroke
				(width 0.1524)
				(type default)
			)
			(layer "F.SilkS")
		)
		(fp_line
			(start 0.7874 0.4064)
			(end -0.7874 0.4064)
			(stroke
				(width 0.1524)
				(type default)
			)
			(layer "F.SilkS")
		)
		(fp_line
			(start -0.7874 0.4064)
			(end -0.7874 -0.4064)
			(stroke
				(width 0.1524)
				(type default)
			)
			(layer "F.SilkS")
		)
		(fp_line
			(start -0.12065 -0.305054)
			(end -0.12065 -0.2794)
			(stroke
				(width 0.1)
				(type default)
			)
			(layer "F.Fab")
		)
		(fp_line
			(start -0.67945 -0.305054)
			(end -0.12065 -0.305054)
			(stroke
				(width 0.1)
				(type default)
			)
			(layer "F.Fab")
		)
		(fp_line
			(start 0.67945 -0.3048)
			(end 0.67945 0.3048)
			(stroke
				(width 0.1)
				(type default)
			)
			(layer "F.Fab")
		)
		(fp_line
			(start 0.12065 -0.3048)
			(end 0.67945 -0.3048)
			(stroke
				(width 0.1)
				(type default)
			)
			(layer "F.Fab")
		)
		(fp_line
			(start 0.12065 -0.2794)
			(end 0.12065 -0.3048)
			(stroke
				(width 0.1)
				(type default)
			)
			(layer "F.Fab")
		)
		(fp_line
			(start -0.12065 -0.2794)
			(end 0.12065 -0.2794)
			(stroke
				(width 0.1)
				(type default)
			)
			(layer "F.Fab")
		)
		(fp_line
			(start 0.120396 0.2794)
			(end -0.12065 0.2794)
			(stroke
				(width 0.1)
				(type default)
			)
			(layer "F.Fab")
		)
		(fp_line
			(start -0.12065 0.2794)
			(end -0.12065 0.3048)
			(stroke
				(width 0.1)
				(type default)
			)
			(layer "F.Fab")
		)
		(fp_line
			(start 0.67945 0.3048)
			(end 0.120396 0.3048)
			(stroke
				(width 0.1)
				(type default)
			)
			(layer "F.Fab")
		)
		(fp_line
			(start 0.120396 0.3048)
			(end 0.120396 0.2794)
			(stroke
				(width 0.1)
				(type default)
			)
			(layer "F.Fab")
		)
		(fp_line
			(start -0.12065 0.3048)
			(end -0.67945 0.3048)
			(stroke
				(width 0.1)
				(type default)
			)
			(layer "F.Fab")
		)
		(fp_line
			(start -0.67945 0.3048)
			(end -0.67945 -0.305054)
			(stroke
				(width 0.1)
				(type default)
			)
			(layer "F.Fab")
		)
		(pad "1" smd circle
			(at -0.40005 0 90)
			(size 0 0)
			(layers "F.Cu" "F.Mask" "F.Paste")
			(net "P3V3_AUX")
		)
		(pad "2" smd circle
			(at 0.40005 0 90)
			(size 0 0)
			(layers "F.Cu" "F.Mask" "F.Paste")
			(net "JTAG_BIC_TMS_R")
		)
	)
	(footprint ""
		(layer "F.Cu")
		(at 440.292744 -118.446804)
		(property "Reference" "PC913"
			(at 0 0 0)
			(layer "F.SilkS")
			(hide yes)
			(effects
				(font
					(size 1.27 1.27)
				)
			)
		)
		(property "Value" ""
			(at 0 0 0)
			(layer "F.Fab")
			(effects
				(font
					(size 1.27 1.27)
				)
			)
		)
		(duplicate_pad_numbers_are_jumpers no)
		(fp_line
			(start -1.524 -0.762)
			(end 1.524 -0.762)
			(stroke
				(width 0.1524)
				(type default)
			)
			(layer "F.SilkS")
		)
		(fp_line
			(start -1.524 0.762)
			(end -1.524 -0.762)
			(stroke
				(width 0.1524)
				(type default)
			)
			(layer "F.SilkS")
		)
		(fp_line
			(start 1.524 -0.762)
			(end 1.524 0.762)
			(stroke
				(width 0.1524)
				(type default)
			)
			(layer "F.SilkS")
		)
		(fp_line
			(start 1.524 0.762)
			(end -1.524 0.762)
			(stroke
				(width 0.1524)
				(type default)
			)
			(layer "F.SilkS")
		)
		(fp_line
			(start -1.1049 -0.724916)
			(end -1.1049 0.724916)
			(stroke
				(width 0.1)
				(type default)
			)
			(layer "F.Fab")
		)
		(fp_line
			(start -1.1049 0.724916)
			(end 1.1049 0.724916)
			(stroke
				(width 0.1)
				(type default)
			)
			(layer "F.Fab")
		)
		(fp_line
			(start 1.1049 -0.724916)
			(end -1.1049 -0.724916)
			(stroke
				(width 0.1)
				(type default)
			)
			(layer "F.Fab")
		)
		(fp_line
			(start 1.1049 0.724916)
			(end 1.1049 -0.724916)
			(stroke
				(width 0.1)
				(type default)
			)
			(layer "F.Fab")
		)
		(pad "1" smd rect
			(at -0.889 0 180)
			(size 1.016 1.27)
			(layers "F.Cu" "F.Mask" "F.Paste")
			(net "P3V3_NIC7")
		)
		(pad "2" smd rect
			(at 0.889 0 180)
			(size 1.016 1.27)
			(layers "F.Cu" "F.Mask" "F.Paste")
			(net "GND")
		)
	)
	(footprint ""
		(layer "F.Cu")
		(at 253.713488 -254.753364 -90)
		(property "Reference" "R6155"
			(at 0 0 270)
			(layer "F.SilkS")
			(hide yes)
			(effects
				(font
					(size 1.27 1.27)
				)
			)
		)
		(property "Value" ""
			(at 0 0 270)
			(layer "F.Fab")
			(effects
				(font
					(size 1.27 1.27)
				)
			)
		)
		(duplicate_pad_numbers_are_jumpers no)
		(fp_line
			(start -0.7874 0.4064)
			(end -0.7874 -0.4064)
			(stroke
				(width 0.1524)
				(type default)
			)
			(layer "F.SilkS")
		)
		(fp_line
			(start 0.7874 0.4064)
			(end -0.7874 0.4064)
			(stroke
				(width 0.1524)
				(type default)
			)
			(layer "F.SilkS")
		)
		(fp_line
			(start -0.7874 -0.4064)
			(end 0.7874 -0.4064)
			(stroke
				(width 0.1524)
				(type default)
			)
			(layer "F.SilkS")
		)
		(fp_line
			(start 0.7874 -0.4064)
			(end 0.7874 0.4064)
			(stroke
				(width 0.1524)
				(type default)
			)
			(layer "F.SilkS")
		)
		(fp_line
			(start -0.67945 0.3048)
			(end -0.67945 -0.305054)
			(stroke
				(width 0.1)
				(type default)
			)
			(layer "F.Fab")
		)
		(fp_line
			(start -0.12065 0.3048)
			(end -0.67945 0.3048)
			(stroke
				(width 0.1)
				(type default)
			)
			(layer "F.Fab")
		)
		(fp_line
			(start 0.120396 0.3048)
			(end 0.120396 0.2794)
			(stroke
				(width 0.1)
				(type default)
			)
			(layer "F.Fab")
		)
		(fp_line
			(start 0.67945 0.3048)
			(end 0.120396 0.3048)
			(stroke
				(width 0.1)
				(type default)
			)
			(layer "F.Fab")
		)
		(fp_line
			(start -0.12065 0.2794)
			(end -0.12065 0.3048)
			(stroke
				(width 0.1)
				(type default)
			)
			(layer "F.Fab")
		)
		(fp_line
			(start 0.120396 0.2794)
			(end -0.12065 0.2794)
			(stroke
				(width 0.1)
				(type default)
			)
			(layer "F.Fab")
		)
		(fp_line
			(start -0.12065 -0.2794)
			(end 0.12065 -0.2794)
			(stroke
				(width 0.1)
				(type default)
			)
			(layer "F.Fab")
		)
		(fp_line
			(start 0.12065 -0.2794)
			(end 0.12065 -0.3048)
			(stroke
				(width 0.1)
				(type default)
			)
			(layer "F.Fab")
		)
		(fp_line
			(start 0.12065 -0.3048)
			(end 0.67945 -0.3048)
			(stroke
				(width 0.1)
				(type default)
			)
			(layer "F.Fab")
		)
		(fp_line
			(start 0.67945 -0.3048)
			(end 0.67945 0.3048)
			(stroke
				(width 0.1)
				(type default)
			)
			(layer "F.Fab")
		)
		(fp_line
			(start -0.67945 -0.305054)
			(end -0.12065 -0.305054)
			(stroke
				(width 0.1)
				(type default)
			)
			(layer "F.Fab")
		)
		(fp_line
			(start -0.12065 -0.305054)
			(end -0.12065 -0.2794)
			(stroke
				(width 0.1)
				(type default)
			)
			(layer "F.Fab")
		)
		(pad "1" smd circle
			(at -0.40005 0 270)
			(size 0 0)
			(layers "F.Cu" "F.Mask" "F.Paste")
			(net "PEX2_SYS_ERR_R_N")
		)
		(pad "2" smd circle
			(at 0.40005 0 270)
			(size 0 0)
			(layers "F.Cu" "F.Mask" "F.Paste")
			(net "P1V8_PEX")
		)
	)
	(footprint ""
		(layer "F.Cu")
		(at 260.205474 -258.511548 -90)
		(property "Reference" "C3422"
			(at 0 0 270)
			(layer "F.SilkS")
			(hide yes)
			(effects
				(font
					(size 1.27 1.27)
				)
			)
		)
		(property "Value" ""
			(at 0 0 270)
			(layer "F.Fab")
			(effects
				(font
					(size 1.27 1.27)
				)
			)
		)
		(duplicate_pad_numbers_are_jumpers no)
		(fp_line
			(start -1.2954 0.5842)
			(end -1.2954 -0.5842)
			(stroke
				(width 0.1524)
				(type default)
			)
			(layer "F.SilkS")
		)
		(fp_line
			(start 1.2954 0.5842)
			(end -1.2954 0.5842)
			(stroke
				(width 0.1524)
				(type default)
			)
			(layer "F.SilkS")
		)
		(fp_line
			(start -1.2954 -0.5842)
			(end 1.2954 -0.5842)
			(stroke
				(width 0.1524)
				(type default)
			)
			(layer "F.SilkS")
		)
		(fp_line
			(start 1.2954 -0.5842)
			(end 1.2954 0.5842)
			(stroke
				(width 0.1524)
				(type default)
			)
			(layer "F.SilkS")
		)
		(fp_line
			(start -0.8636 0.4572)
			(end -0.8636 0.4064)
			(stroke
				(width 0.1)
				(type default)
			)
			(layer "F.Fab")
		)
		(fp_line
			(start 0.8636 0.4572)
			(end -0.8636 0.4572)
			(stroke
				(width 0.1)
				(type default)
			)
			(layer "F.Fab")
		)
		(fp_line
			(start -1.1938 0.4064)
			(end -1.1938 -0.4064)
			(stroke
				(width 0.1)
				(type default)
			)
			(layer "F.Fab")
		)
		(fp_line
			(start -0.8636 0.4064)
			(end -1.1938 0.4064)
			(stroke
				(width 0.1)
				(type default)
			)
			(layer "F.Fab")
		)
		(fp_line
			(start 0.8636 0.4064)
			(end 0.8636 0.4572)
			(stroke
				(width 0.1)
				(type default)
			)
			(layer "F.Fab")
		)
		(fp_line
			(start 1.1938 0.4064)
			(end 0.8636 0.4064)
			(stroke
				(width 0.1)
				(type default)
			)
			(layer "F.Fab")
		)
		(fp_line
			(start -1.1938 -0.4064)
			(end -0.8636 -0.4064)
			(stroke
				(width 0.1)
				(type default)
			)
			(layer "F.Fab")
		)
		(fp_line
			(start -0.8636 -0.4064)
			(end -0.8636 -0.4572)
			(stroke
				(width 0.1)
				(type default)
			)
			(layer "F.Fab")
		)
		(fp_line
			(start 0.8636 -0.4064)
			(end 1.1938 -0.4064)
			(stroke
				(width 0.1)
				(type default)
			)
			(layer "F.Fab")
		)
		(fp_line
			(start 1.1938 -0.4064)
			(end 1.1938 0.4064)
			(stroke
				(width 0.1)
				(type default)
			)
			(layer "F.Fab")
		)
		(fp_line
			(start -0.8636 -0.4572)
			(end 0.8636 -0.4572)
			(stroke
				(width 0.1)
				(type default)
			)
			(layer "F.Fab")
		)
		(fp_line
			(start 0.8636 -0.4572)
			(end 0.8636 -0.4064)
			(stroke
				(width 0.1)
				(type default)
			)
			(layer "F.Fab")
		)
		(pad "1" smd rect
			(at -0.7366 0 180)
			(size 0.7112 0.8128)
			(layers "F.Cu" "F.Mask" "F.Paste")
			(net "P1V8_VDDA_PEX2_R")
		)
		(pad "2" smd rect
			(at 0.7366 0 180)
			(size 0.7112 0.8128)
			(layers "F.Cu" "F.Mask" "F.Paste")
			(net "GND")
		)
	)
)
